(kicad_pcb
	(version 20241229)
	(generator "pcbnew")
	(generator_version "9.0")
	(general
		(thickness 1.6296)
		(legacy_teardrops no)
	)
	(paper "A3")
	(title_block
		(title "Thunderbolt to 10GbE adapter")
		(date "2026-04-21")
		(rev "1.1.0")
		(company "Antmicro Ltd")
		(comment 1 "www.antmicro.com")
		(comment 9 "footprints 248-252 of 703")
	)
	(layers
		(0 "F.Cu" signal)
		(4 "In1.Cu" signal)
		(6 "In2.Cu" signal)
		(8 "In3.Cu" signal)
		(10 "In4.Cu" signal)
		(12 "In5.Cu" signal)
		(14 "In6.Cu" signal)
		(2 "B.Cu" signal)
		(9 "F.Adhes" user "F.Adhesive")
		(11 "B.Adhes" user "B.Adhesive")
		(13 "F.Paste" user)
		(15 "B.Paste" user)
		(5 "F.SilkS" user "F.Silkscreen")
		(7 "B.SilkS" user "B.Silkscreen")
		(1 "F.Mask" user)
		(3 "B.Mask" user)
		(17 "Dwgs.User" user "User.Drawings")
		(19 "Cmts.User" user "User.Comments")
		(21 "Eco1.User" user "User.Eco1")
		(23 "Eco2.User" user "User.Eco2")
		(25 "Edge.Cuts" user)
		(27 "Margin" user)
		(31 "F.CrtYd" user "F.Courtyard")
		(29 "B.CrtYd" user "B.Courtyard")
		(35 "F.Fab" user)
		(33 "B.Fab" user)
	)
	(footprint "antmicro-footprints:R_0402_1005Metric"
		(layer "F.Cu")
		(at 137 60.4)
		(descr "Resistor SMD 0402")
		(tags "resistor SMD 0402")
		(property "Reference" "R236"
			(at 0.6 5.8 0)
			(layer "F.SilkS")
			(effects
				(font
					(size 0.7 0.7)
					(thickness 0.15)
				)
				(justify left bottom)
			)
		)
		(property "Value" "R_0R_0402"
			(at -1.011843 1.772047 0)
			(layer "F.Fab")
			(effects
				(font
					(size 0.7 0.7)
					(thickness 0.15)
				)
				(justify left bottom)
			)
		)
		(property "Datasheet" "https://industrial.panasonic.com/cdbs/www-data/pdf/RDA0000/AOA0000C301.pdf"
			(at 0 0 0)
			(layer "F.Fab")
			(hide yes)
			(effects
				(font
					(size 1.27 1.27)
					(thickness 0.15)
				)
			)
		)
		(property "Description" "SMD Chip Resistor, Jumper, 0 ohm, 100 mW, 0402 [1005 Metric], Thick Film, General Purpose"
			(at 0 0 0)
			(layer "F.Fab")
			(hide yes)
			(effects
				(font
					(size 1.27 1.27)
					(thickness 0.15)
				)
			)
		)
		(property "MPN" "ERJ2GE0R00X"
			(at 0 0 0)
			(unlocked yes)
			(layer "F.Fab")
			(hide yes)
			(effects
				(font
					(size 1 1)
					(thickness 0.15)
				)
			)
		)
		(property "Manufacturer" "Panasonic"
			(at 0 0 0)
			(unlocked yes)
			(layer "F.Fab")
			(hide yes)
			(effects
				(font
					(size 1 1)
					(thickness 0.15)
				)
			)
		)
		(property "License" "Apache-2.0"
			(at 0 0 0)
			(unlocked yes)
			(layer "F.Fab")
			(hide yes)
			(effects
				(font
					(size 1 1)
					(thickness 0.15)
				)
			)
		)
		(property "Author" "Antmicro"
			(at 0 0 0)
			(unlocked yes)
			(layer "F.Fab")
			(hide yes)
			(effects
				(font
					(size 1 1)
					(thickness 0.15)
				)
			)
		)
		(property "Val" "0R"
			(at 0 0 0)
			(unlocked yes)
			(layer "F.Fab")
			(hide yes)
			(effects
				(font
					(size 1 1)
					(thickness 0.15)
				)
			)
		)
		(property "Tolerance" "~"
			(at 0 0 0)
			(unlocked yes)
			(layer "F.Fab")
			(hide yes)
			(effects
				(font
					(size 1 1)
					(thickness 0.15)
				)
			)
		)
		(property "Current" "1A"
			(at 0 0 0)
			(unlocked yes)
			(layer "F.Fab")
			(hide yes)
			(effects
				(font
					(size 1 1)
					(thickness 0.15)
				)
			)
		)
		(sheetname "/Power input/")
		(sheetfile "power_input.kicad_sch")
		(attr smd)
		(fp_rect
			(start -0.925 -0.47)
			(end 0.925 0.47)
			(stroke
				(width 0.05)
				(type default)
			)
			(fill no)
			(layer "F.CrtYd")
		)
		(fp_rect
			(start -0.5 -0.25)
			(end 0.5 0.25)
			(stroke
				(width 0.15)
				(type solid)
			)
			(fill no)
			(layer "F.Fab")
		)
		(fp_text user "Author: Antmicro"
			(at -0.95 4.169 0)
			(layer "F.Fab")
			(effects
				(font
					(size 0.7 0.7)
					(thickness 0.15)
				)
				(justify left bottom)
			)
		)
		(fp_text user "License: Apache-2.0"
			(at -0.95 5.169 0)
			(layer "F.Fab")
			(effects
				(font
					(size 0.7 0.7)
					(thickness 0.15)
				)
				(justify left bottom)
			)
		)
		(fp_text user "${REFERENCE}"
			(at -0.95 3.168 0)
			(layer "F.Fab")
			(effects
				(font
					(size 0.7 0.7)
					(thickness 0.15)
				)
				(justify left bottom)
			)
		)
		(pad "1" smd roundrect
			(at -0.48 0)
			(size 0.59 0.64)
			(layers "F.Cu" "F.Mask" "F.Paste")
			(roundrect_rratio 0.25)
			(net 13 "/Power input/5V_JACK")
			(pintype "passive")
		)
		(pad "2" smd roundrect
			(at 0.48 0)
			(size 0.59 0.64)
			(layers "F.Cu" "F.Mask" "F.Paste")
			(roundrect_rratio 0.25)
			(net 433 "Net-(Q8-G)")
			(pintype "passive")
		)
	)
	(footprint "antmicro-footprints:C_2220_5650Metric"
		(layer "F.Cu")
		(at 143 51 90)
		(descr "Capacitor SMD 2220")
		(tags "capacitor SMD 2220")
		(property "Reference" "C311"
			(at 3.6 0.25 180)
			(layer "F.SilkS")
			(effects
				(font
					(size 0.7 0.7)
					(thickness 0.15)
				)
				(justify left bottom)
			)
		)
		(property "Value" "C_22u_100V_2220"
			(at 0 3.9 90)
			(layer "F.Fab")
			(effects
				(font
					(size 0.7 0.7)
					(thickness 0.15)
				)
				(justify left bottom)
			)
		)
		(property "Datasheet" "https://product.tdk.com/en/search/capacitor/ceramic/mlcc/info?part_no=C5750X7S2A226M280KB"
			(at 0 0 90)
			(layer "F.Fab")
			(hide yes)
			(effects
				(font
					(size 1.27 1.27)
					(thickness 0.15)
				)
			)
		)
		(property "Description" "SMT Multilayer Ceramic Capacitor, 22 µF, 100 V, 2220 [5750 Metric], ± 20%, X7S, C"
			(at 0 0 90)
			(layer "F.Fab")
			(hide yes)
			(effects
				(font
					(size 1.27 1.27)
					(thickness 0.15)
				)
			)
		)
		(property "MPN" "C5750X7S2A226M280KB"
			(at 0 0 90)
			(unlocked yes)
			(layer "F.Fab")
			(hide yes)
			(effects
				(font
					(size 1 1)
					(thickness 0.15)
				)
			)
		)
		(property "Manufacturer" "TDK"
			(at 0 0 90)
			(unlocked yes)
			(layer "F.Fab")
			(hide yes)
			(effects
				(font
					(size 1 1)
					(thickness 0.15)
				)
			)
		)
		(property "License" "Apache-2.0"
			(at 0 0 90)
			(unlocked yes)
			(layer "F.Fab")
			(hide yes)
			(effects
				(font
					(size 1 1)
					(thickness 0.15)
				)
			)
		)
		(property "Author" "Antmicro"
			(at 0 0 90)
			(unlocked yes)
			(layer "F.Fab")
			(hide yes)
			(effects
				(font
					(size 1 1)
					(thickness 0.15)
				)
			)
		)
		(property "Val" "22u"
			(at 0 0 90)
			(unlocked yes)
			(layer "F.Fab")
			(hide yes)
			(effects
				(font
					(size 1 1)
					(thickness 0.15)
				)
			)
		)
		(property "Voltage" "100V"
			(at 0 0 90)
			(unlocked yes)
			(layer "F.Fab")
			(hide yes)
			(effects
				(font
					(size 1 1)
					(thickness 0.15)
				)
			)
		)
		(property "Dielectric" "X7S"
			(at 0 0 90)
			(unlocked yes)
			(layer "F.Fab")
			(hide yes)
			(effects
				(font
					(size 1 1)
					(thickness 0.15)
				)
			)
		)
		(property "Public" "False"
			(at 0 0 90)
			(unlocked yes)
			(layer "F.Fab")
			(hide yes)
			(effects
				(font
					(size 1 1)
					(thickness 0.15)
				)
			)
		)
		(sheetname "/Power input/")
		(sheetfile "power_input.kicad_sch")
		(attr smd)
		(fp_line
			(start -1.415 -2.61)
			(end 1.415 -2.61)
			(stroke
				(width 0.15)
				(type solid)
			)
			(layer "F.SilkS")
		)
		(fp_line
			(start -1.415 2.61)
			(end 1.415 2.61)
			(stroke
				(width 0.15)
				(type solid)
			)
			(layer "F.SilkS")
		)
		(fp_rect
			(start -3.7 -2.95)
			(end 3.7 2.95)
			(stroke
				(width 0.05)
				(type solid)
			)
			(fill no)
			(layer "F.CrtYd")
		)
		(fp_rect
			(start -2.85 -2.5)
			(end 2.85 2.5)
			(stroke
				(width 0.15)
				(type solid)
			)
			(fill no)
			(layer "F.Fab")
		)
		(fp_text user "License: Apache-2.0"
			(at -3.7 6.9 90)
			(layer "F.Fab")
			(effects
				(font
					(size 0.7 0.7)
					(thickness 0.15)
				)
				(justify left bottom)
			)
		)
		(fp_text user "${REFERENCE}"
			(at -3.7 5.9 90)
			(layer "F.Fab")
			(effects
				(font
					(size 0.7 0.7)
					(thickness 0.15)
				)
				(justify left bottom)
			)
		)
		(fp_text user "Author: Antmicro"
			(at -3.7 7.9 90)
			(layer "F.Fab")
			(effects
				(font
					(size 0.7 0.7)
					(thickness 0.15)
				)
				(justify left bottom)
			)
		)
		(pad "1" smd roundrect
			(at -2.55 0 90)
			(size 1.8 5.4)
			(layers "F.Cu" "F.Mask" "F.Paste")
			(roundrect_rratio 0.138889)
			(net 23 "GND")
			(pintype "passive")
		)
		(pad "2" smd roundrect
			(at 2.55 0 90)
			(size 1.8 5.4)
			(layers "F.Cu" "F.Mask" "F.Paste")
			(roundrect_rratio 0.138889)
			(net 412 "Net-(D15-C)")
			(pintype "passive")
		)
	)
	(footprint "antmicro-footprints:C_0603_1608Metric_EIA"
		(layer "F.Cu")
		(at 154.900001 114.35)
		(descr "Capacitor SMD 0603, IPC-7351 Density Level A")
		(tags "Capacitor 0603")
		(property "Reference" "C106"
			(at 13.650003 16.600001 0)
			(layer "F.SilkS")
			(effects
				(font
					(size 0.7 0.7)
					(thickness 0.15)
				)
			)
		)
		(property "Value" "C_22u_16V_0603"
			(at -1.42757 1.770288 0)
			(layer "F.Fab")
			(effects
				(font
					(size 0.7 0.7)
					(thickness 0.15)
				)
				(justify left bottom)
			)
		)
		(property "Datasheet" "https://product.samsungsem.com/mlcc/CL10A226MO7JZN.do"
			(at 0 0 0)
			(layer "F.Fab")
			(hide yes)
			(effects
				(font
					(size 1.27 1.27)
					(thickness 0.15)
				)
			)
		)
		(property "Description" "SMD Multilayer Ceramic Capacitor"
			(at 0 0 0)
			(layer "F.Fab")
			(hide yes)
			(effects
				(font
					(size 1.27 1.27)
					(thickness 0.15)
				)
			)
		)
		(property "MPN" "CL10A226MO7JZNC"
			(at 0 0 0)
			(unlocked yes)
			(layer "F.Fab")
			(hide yes)
			(effects
				(font
					(size 1 1)
					(thickness 0.15)
				)
			)
		)
		(property "Manufacturer" "Samsung Electro-Mechanics"
			(at 0 0 0)
			(unlocked yes)
			(layer "F.Fab")
			(hide yes)
			(effects
				(font
					(size 1 1)
					(thickness 0.15)
				)
			)
		)
		(property "License" "Apache-2.0"
			(at 0 0 0)
			(unlocked yes)
			(layer "F.Fab")
			(hide yes)
			(effects
				(font
					(size 1 1)
					(thickness 0.15)
				)
			)
		)
		(property "Author" "Antmicro"
			(at 0 0 0)
			(unlocked yes)
			(layer "F.Fab")
			(hide yes)
			(effects
				(font
					(size 1 1)
					(thickness 0.15)
				)
			)
		)
		(property "Val" "22u"
			(at 0 0 0)
			(unlocked yes)
			(layer "F.Fab")
			(hide yes)
			(effects
				(font
					(size 1 1)
					(thickness 0.15)
				)
			)
		)
		(property "Voltage" "16V"
			(at 0 0 0)
			(unlocked yes)
			(layer "F.Fab")
			(hide yes)
			(effects
				(font
					(size 1 1)
					(thickness 0.15)
				)
			)
		)
		(property "Dielectric" ""
			(at 0 0 0)
			(unlocked yes)
			(layer "F.Fab")
			(hide yes)
			(effects
				(font
					(size 1 1)
					(thickness 0.15)
				)
			)
		)
		(sheetname "/X710 DCDC converters/")
		(sheetfile "DCDC_converters_X710.kicad_sch")
		(attr smd)
		(fp_line
			(start -0.15 -0.55)
			(end 0.15 -0.55)
			(stroke
				(width 0.15)
				(type solid)
			)
			(layer "F.SilkS")
		)
		(fp_line
			(start -0.15 0.55)
			(end 0.15 0.55)
			(stroke
				(width 0.15)
				(type solid)
			)
			(layer "F.SilkS")
		)
		(fp_rect
			(start -1.25 -0.65)
			(end 1.25 0.65)
			(stroke
				(width 0.05)
				(type solid)
			)
			(fill no)
			(layer "F.CrtYd")
		)
		(fp_rect
			(start -0.8 -0.45)
			(end 0.8 0.45)
			(stroke
				(width 0.15)
				(type solid)
			)
			(fill no)
			(layer "F.Fab")
		)
		(fp_text user "Author: Antmicro"
			(at -1.682 4.894 0)
			(layer "F.Fab")
			(effects
				(font
					(size 0.7 0.7)
					(thickness 0.15)
				)
				(justify left bottom)
			)
		)
		(fp_text user "License: Apache-2.0"
			(at -1.682 5.895 0)
			(layer "F.Fab")
			(effects
				(font
					(size 0.7 0.7)
					(thickness 0.15)
				)
				(justify left bottom)
			)
		)
		(fp_text user "${REFERENCE}"
			(at -1.682 3.895 0)
			(layer "F.Fab")
			(effects
				(font
					(size 0.7 0.7)
					(thickness 0.15)
				)
				(justify left bottom)
			)
		)
		(pad "1" smd roundrect
			(at -0.7 0)
			(size 0.8 1.1)
			(layers "F.Cu" "F.Mask" "F.Paste")
			(roundrect_rratio 0.2)
			(net 23 "GND")
			(pintype "passive")
		)
		(pad "2" smd roundrect
			(at 0.7 0)
			(size 0.8 1.1)
			(layers "F.Cu" "F.Mask" "F.Paste")
			(roundrect_rratio 0.2)
			(net 40 "+5V")
			(pintype "passive")
		)
	)
	(footprint "antmicro-footprints:C_0402_1005Metric"
		(layer "F.Cu")
		(at 138 78.75)
		(descr "Capacitor SMD 0402")
		(tags "capacitor SMD 0402")
		(property "Reference" "C268"
			(at -3.8 0.45 0)
			(layer "F.SilkS")
			(effects
				(font
					(size 0.7 0.7)
					(thickness 0.15)
				)
				(justify left bottom)
			)
		)
		(property "Value" "C_220n_16V_0402"
			(at -1.022927 2.155213 0)
			(layer "F.Fab")
			(effects
				(font
					(size 0.7 0.7)
					(thickness 0.15)
				)
				(justify left bottom)
			)
		)
		(property "Datasheet" "https://www.murata.com/products/productdetail?partno=GRM155R71C224KA12%23"
			(at 0 0 0)
			(layer "F.Fab")
			(hide yes)
			(effects
				(font
					(size 1.27 1.27)
					(thickness 0.15)
				)
			)
		)
		(property "Description" "SMD Multilayer Ceramic Capacitor, 0.22 µF, 16 V, 0402 [1005 Metric], ± 10%, X7R, GRM Series"
			(at 0 0 0)
			(layer "F.Fab")
			(hide yes)
			(effects
				(font
					(size 1.27 1.27)
					(thickness 0.15)
				)
			)
		)
		(property "MPN" "GRM155R71C224KA12D"
			(at 0 0 0)
			(unlocked yes)
			(layer "F.Fab")
			(hide yes)
			(effects
				(font
					(size 1 1)
					(thickness 0.15)
				)
			)
		)
		(property "Manufacturer" "Murata"
			(at 0 0 0)
			(unlocked yes)
			(layer "F.Fab")
			(hide yes)
			(effects
				(font
					(size 1 1)
					(thickness 0.15)
				)
			)
		)
		(property "License" "Apache-2.0"
			(at 0 0 0)
			(unlocked yes)
			(layer "F.Fab")
			(hide yes)
			(effects
				(font
					(size 1 1)
					(thickness 0.15)
				)
			)
		)
		(property "Author" "Antmicro"
			(at 0 0 0)
			(unlocked yes)
			(layer "F.Fab")
			(hide yes)
			(effects
				(font
					(size 1 1)
					(thickness 0.15)
				)
			)
		)
		(property "Val" "220n"
			(at 0 0 0)
			(unlocked yes)
			(layer "F.Fab")
			(hide yes)
			(effects
				(font
					(size 1 1)
					(thickness 0.15)
				)
			)
		)
		(property "Voltage" "16V"
			(at 0 0 0)
			(unlocked yes)
			(layer "F.Fab")
			(hide yes)
			(effects
				(font
					(size 1 1)
					(thickness 0.15)
				)
			)
		)
		(property "Dielectric" "X7R"
			(at 0 0 0)
			(unlocked yes)
			(layer "F.Fab")
			(hide yes)
			(effects
				(font
					(size 1 1)
					(thickness 0.15)
				)
			)
		)
		(sheetname "/X710-AT2 PCIe/")
		(sheetfile "x710-at2-pcie.kicad_sch")
		(attr smd)
		(fp_rect
			(start -0.925 -0.47)
			(end 0.925 0.47)
			(stroke
				(width 0.05)
				(type default)
			)
			(fill no)
			(layer "F.CrtYd")
		)
		(fp_line
			(start -0.494 -0.25)
			(end 0.504 -0.25)
			(stroke
				(width 0.15)
				(type solid)
			)
			(layer "F.Fab")
		)
		(fp_line
			(start -0.494 0.248)
			(end -0.494 -0.25)
			(stroke
				(width 0.15)
				(type solid)
			)
			(layer "F.Fab")
		)
		(fp_line
			(start 0.504 -0.25)
			(end 0.504 0.248)
			(stroke
				(width 0.15)
				(type solid)
			)
			(layer "F.Fab")
		)
		(fp_line
			(start 0.504 0.248)
			(end -0.494 0.248)
			(stroke
				(width 0.15)
				(type solid)
			)
			(layer "F.Fab")
		)
		(fp_text user "License: Apache-2.0"
			(at -0.939 5.799 0)
			(layer "F.Fab")
			(effects
				(font
					(size 0.7 0.7)
					(thickness 0.15)
				)
				(justify left bottom)
			)
		)
		(fp_text user "Author: Antmicro"
			(at -0.939 3.399 0)
			(layer "F.Fab")
			(effects
				(font
					(size 0.7 0.7)
					(thickness 0.15)
				)
				(justify left bottom)
			)
		)
		(fp_text user "${REFERENCE}"
			(at -0.939 4.599 0)
			(layer "F.Fab")
			(effects
				(font
					(size 0.7 0.7)
					(thickness 0.15)
				)
				(justify left bottom)
			)
		)
		(pad "1" smd roundrect
			(at -0.48 0)
			(size 0.59 0.64)
			(layers "F.Cu" "F.Mask" "F.Paste")
			(roundrect_rratio 0.25)
			(net 598 "/TB Controller/PCIex4.TX2-")
			(pintype "passive")
		)
		(pad "2" smd roundrect
			(at 0.48 0)
			(size 0.59 0.64)
			(layers "F.Cu" "F.Mask" "F.Paste")
			(roundrect_rratio 0.25)
			(net 32 "/X710-AT2 PCIe/PCIe_{x4}_AC.TX2-")
			(pintype "passive")
		)
	)
	(footprint "antmicro-footprints:C_0402_1005Metric"
		(layer "F.Cu")
		(at 117.8 122 180)
		(descr "Capacitor SMD 0402")
		(tags "capacitor SMD 0402")
		(property "Reference" "C49"
			(at -0.8 -0.2 180)
			(layer "F.SilkS")
			(effects
				(font
					(size 0.7 0.7)
					(thickness 0.15)
				)
				(justify left bottom)
			)
		)
		(property "Value" "C_220n_0402"
			(at -1.022927 2.155213 180)
			(layer "F.Fab")
			(effects
				(font
					(size 0.7 0.7)
					(thickness 0.15)
				)
				(justify left bottom)
			)
		)
		(property "Datasheet" "https://www.yageo.com/en/Chart/Download/pdf/CC0402KRX5R6BB224"
			(at 0 0 180)
			(layer "F.Fab")
			(hide yes)
			(effects
				(font
					(size 1.27 1.27)
					(thickness 0.15)
				)
			)
		)
		(property "Description" "SMD Multilayer Ceramic Capacitor, 0.22 µF, 10 V, 0402 [1005 Metric], ± 10%, X5R, CC Series"
			(at 0 0 180)
			(layer "F.Fab")
			(hide yes)
			(effects
				(font
					(size 1.27 1.27)
					(thickness 0.15)
				)
			)
		)
		(property "MPN" "CC0402KRX5R6BB224"
			(at 0 0 180)
			(unlocked yes)
			(layer "F.Fab")
			(hide yes)
			(effects
				(font
					(size 1 1)
					(thickness 0.15)
				)
			)
		)
		(property "Manufacturer" "YAGEO"
			(at 0 0 180)
			(unlocked yes)
			(layer "F.Fab")
			(hide yes)
			(effects
				(font
					(size 1 1)
					(thickness 0.15)
				)
			)
		)
		(property "License" "Apache-2.0"
			(at 0 0 180)
			(unlocked yes)
			(layer "F.Fab")
			(hide yes)
			(effects
				(font
					(size 1 1)
					(thickness 0.15)
				)
			)
		)
		(property "Val" "220n"
			(at 0 0 180)
			(unlocked yes)
			(layer "F.Fab")
			(hide yes)
			(effects
				(font
					(size 1 1)
					(thickness 0.15)
				)
			)
		)
		(property "Voltage" ""
			(at 0 0 180)
			(unlocked yes)
			(layer "F.Fab")
			(hide yes)
			(effects
				(font
					(size 1 1)
					(thickness 0.15)
				)
			)
		)
		(property "Dielectric" ""
			(at 0 0 180)
			(unlocked yes)
			(layer "F.Fab")
			(hide yes)
			(effects
				(font
					(size 1 1)
					(thickness 0.15)
				)
			)
		)
		(property "Author" "Antmicro"
			(at 0 0 180)
			(unlocked yes)
			(layer "F.Fab")
			(hide yes)
			(effects
				(font
					(size 1 1)
					(thickness 0.15)
				)
			)
		)
		(sheetname "/TB Controller/")
		(sheetfile "tb.kicad_sch")
		(attr smd)
		(fp_rect
			(start -0.925 -0.47)
			(end 0.925 0.47)
			(stroke
				(width 0.05)
				(type default)
			)
			(fill no)
			(layer "F.CrtYd")
		)
		(fp_line
			(start 0.504 0.248)
			(end -0.494 0.248)
			(stroke
				(width 0.15)
				(type solid)
			)
			(layer "F.Fab")
		)
		(fp_line
			(start 0.504 -0.25)
			(end 0.504 0.248)
			(stroke
				(width 0.15)
				(type solid)
			)
			(layer "F.Fab")
		)
		(fp_line
			(start -0.494 0.248)
			(end -0.494 -0.25)
			(stroke
				(width 0.15)
				(type solid)
			)
			(layer "F.Fab")
		)
		(fp_line
			(start -0.494 -0.25)
			(end 0.504 -0.25)
			(stroke
				(width 0.15)
				(type solid)
			)
			(layer "F.Fab")
		)
		(fp_text user "Author: Antmicro"
			(at -0.939 3.399 180)
			(layer "F.Fab")
			(effects
				(font
					(size 0.7 0.7)
					(thickness 0.15)
				)
				(justify left bottom)
			)
		)
		(fp_text user "License: Apache-2.0"
			(at -0.939 5.799 180)
			(layer "F.Fab")
			(effects
				(font
					(size 0.7 0.7)
					(thickness 0.15)
				)
				(justify left bottom)
			)
		)
		(fp_text user "${REFERENCE}"
			(at -0.939 4.599 180)
			(layer "F.Fab")
			(effects
				(font
					(size 0.7 0.7)
					(thickness 0.15)
				)
				(justify left bottom)
			)
		)
		(pad "1" smd roundrect
			(at -0.48 0 180)
			(size 0.59 0.64)
			(layers "F.Cu" "F.Mask" "F.Paste")
			(roundrect_rratio 0.25)
			(net 316 "/TB Controller/TB_PCIE_TX1_N")
			(pintype "passive")
		)
		(pad "2" smd roundrect
			(at 0.48 0 180)
			(size 0.59 0.64)
			(layers "F.Cu" "F.Mask" "F.Paste")
			(roundrect_rratio 0.25)
			(net 324 "/TB Controller/PCIex4.RX1-")
			(pintype "passive")
		)
	)
)
